FILE_TYPE = MACRO_DRAWING;
SET COLOR_WIRE YELLOW;
SET COLOR_PROP ORANGE;
SET COLOR_DOT WHITE;
SET COLOR_ARC YELLOW;
SET COLOR_BODY GREEN;
SET COLOR_NOTE PURPLE;
SET PROP_DISPLAY VALUE;
SET PAGE_NUMBER P431;
FORCEADD P1V0..1
(-8575 4075);
FORCEPROP 3 LASTPIN (-8575 4025) SIG_NAME P1V8_CPU0_RT_1D\g
J 0
(-8565 4035);
DISPLAY 0.659574 (-8565 4035);
PAINT MONO (-8565 4035);
DISPLAY INVISIBLE (-8565 4035);
FORCEPROP 1 LAST HDL_POWER P1V8_CPU0_RT_1D
J 1
(-8575 4125);
DISPLAY 0.489362 (-8575 4125);
PAINT SKYBLUE (-8575 4125);
FORCEPROP 2 LAST CDS_LIB pure_quanta_power
J 0
(-8575 4075);
DISPLAY INVISIBLE (-8575 4075);
FORCEPROP 1 LAST PATH I1
J 0
(-8525 4100);
DISPLAY 0.872340 (-8525 4100);
PAINT AQUA (-8525 4100);
DISPLAY INVISIBLE (-8525 4100);
FORCEADD VCC_CORE..1
(-4575 4975);
FORCEPROP 3 LASTPIN (-4575 4925) SIG_NAME P0V9_CPU0_RT3_2A\g
J 0
(-4565 4935);
DISPLAY 0.659574 (-4565 4935);
PAINT MONO (-4565 4935);
DISPLAY INVISIBLE (-4565 4935);
FORCEPROP 1 LAST HDL_POWER P0V9_CPU0_RT3_2A
J 1
(-4575 5025);
DISPLAY 0.617021 (-4575 5025);
PAINT SKYBLUE (-4575 5025);
FORCEPROP 2 LAST CDS_LIB pure_quanta_power
J 0
(-4575 4975);
DISPLAY INVISIBLE (-4575 4975);
FORCEPROP 1 LAST PATH I10
J 0
(-4525 5000);
DISPLAY 0.872340 (-4525 5000);
PAINT AQUA (-4525 5000);
DISPLAY INVISIBLE (-4525 5000);
FORCEADD UNIVERSAL_GND..1
(-3025 1275);
FORCEPROP 3 LASTPIN (-3025 1325) SIG_NAME GND\g
J 0
(-3015 1335);
DISPLAY 0.659574 (-3015 1335);
PAINT MONO (-3015 1335);
DISPLAY INVISIBLE (-3015 1335);
FORCEPROP 2 LAST CDS_LIB pure_quanta_power
J 0
(-3025 1275);
DISPLAY INVISIBLE (-3025 1275);
FORCEPROP 1 LAST HDL_POWER GND
J 1
(-3000 1200);
DISPLAY 0.872340 (-3000 1200);
PAINT GREEN (-3000 1200);
DISPLAY INVISIBLE (-3000 1200);
FORCEPROP 1 LAST PATH I11
J 0
(-2950 1275);
DISPLAY 0.872340 (-2950 1275);
PAINT AQUA (-2950 1275);
DISPLAY INVISIBLE (-2950 1275);
FORCEADD UNIVERSAL_GND..1
(-1350 900);
FORCEPROP 3 LASTPIN (-1350 950) SIG_NAME GND\g
J 0
(-1340 960);
DISPLAY 0.659574 (-1340 960);
PAINT MONO (-1340 960);
DISPLAY INVISIBLE (-1340 960);
FORCEPROP 2 LAST CDS_LIB pure_quanta_power
J 0
(-1350 900);
DISPLAY INVISIBLE (-1350 900);
FORCEPROP 1 LAST HDL_POWER GND
J 1
(-1325 825);
DISPLAY 0.872340 (-1325 825);
PAINT GREEN (-1325 825);
DISPLAY INVISIBLE (-1325 825);
FORCEPROP 1 LAST PATH I12
J 0
(-1275 900);
DISPLAY 0.872340 (-1275 900);
PAINT AQUA (-1275 900);
DISPLAY INVISIBLE (-1275 900);
FORCEADD Q_RES..2
(-1350 1200);
FORCEPROP 1 LAST LOCATION R1125
J 0
(-1305 1325);
DISPLAY 0.978723 (-1305 1325);
FORCEPROP 0 LAST $SEC 1
J 0
(-1300 1375);
DISPLAY 0.680851 (-1300 1375);
PAINT MONO (-1300 1375);
DISPLAY INVISIBLE (-1300 1375);
FORCEPROP 0 LAST CDS_SEC 1
J 0
(-1300 1375);
DISPLAY 0.680851 (-1300 1375);
DISPLAY INVISIBLE (-1300 1375);
FORCEPROP 1 LASTPIN (-1350 1300) $PN 1
J 0
(-1345 1262);
DISPLAY 0.787234 (-1345 1262);
PAINT MONO (-1345 1262);
FORCEPROP 1 LASTPIN (-1350 1100) $PN 2
J 0
(-1345 1110);
DISPLAY 0.787234 (-1345 1110);
PAINT MONO (-1345 1110);
FORCEPROP 1 LAST TOLERANCE 5%
J 0
(-1305 1225);
DISPLAY 0.978723 (-1305 1225);
FORCEPROP 1 LAST MATERIAL CHIP
J 0
(-1310 1125);
DISPLAY 0.978723 (-1310 1125);
FORCEPROP 1 LAST WATTAGE 1/20W
J 0
(-1310 1175);
DISPLAY 0.978723 (-1310 1175);
FORCEPROP 1 LAST VALUE 0
J 0
(-1305 1275);
DISPLAY 0.978723 (-1305 1275);
FORCEPROP 1 LAST PACK_TYPE 0201LF
J 0
(-1310 1025);
DISPLAY 0.978723 (-1310 1025);
FORCEPROP 2 LAST CDS_LIB pure_quanta
J 0
(-1350 1200);
DISPLAY INVISIBLE (-1350 1200);
FORCEPROP 1 LAST PATH I13
J 0
(-1300 1375);
DISPLAY 0.978723 (-1300 1375);
PAINT WHITE (-1300 1375);
DISPLAY INVISIBLE (-1300 1375);
FORCEPROP 1 LAST PART_NUMBER CS00001JE10
J 0
(-1310 1075);
DISPLAY 0.978723 (-1310 1075);
DISPLAY INVISIBLE (-1310 1075);
FORCEADD Q_RES..2
(-1200 1750);
FORCEPROP 1 LAST LOCATION R1126
J 0
(-1155 1875);
DISPLAY 0.978723 (-1155 1875);
FORCEPROP 0 LAST $SEC 1
J 0
(-1150 1925);
DISPLAY 0.680851 (-1150 1925);
PAINT MONO (-1150 1925);
DISPLAY INVISIBLE (-1150 1925);
FORCEPROP 0 LAST CDS_SEC 1
J 0
(-1150 1925);
DISPLAY 0.680851 (-1150 1925);
DISPLAY INVISIBLE (-1150 1925);
FORCEPROP 1 LASTPIN (-1200 1850) $PN 1
J 0
(-1195 1812);
DISPLAY 0.787234 (-1195 1812);
PAINT MONO (-1195 1812);
FORCEPROP 1 LASTPIN (-1200 1650) $PN 2
J 0
(-1195 1660);
DISPLAY 0.787234 (-1195 1660);
PAINT MONO (-1195 1660);
FORCEPROP 1 LAST MATERIAL CHIP
J 0
(-1160 1675);
DISPLAY 0.978723 (-1160 1675);
FORCEPROP 1 LAST TOLERANCE 5%
J 0
(-1155 1775);
DISPLAY 0.978723 (-1155 1775);
FORCEPROP 1 LAST PACK_TYPE 0201LF
J 0
(-1160 1575);
DISPLAY 0.978723 (-1160 1575);
FORCEPROP 1 LAST VALUE 0
J 0
(-1155 1825);
DISPLAY 0.978723 (-1155 1825);
FORCEPROP 1 LAST WATTAGE 1/20W
J 0
(-1160 1725);
DISPLAY 0.978723 (-1160 1725);
FORCEPROP 2 LAST CDS_LIB pure_quanta
J 0
(-1200 1750);
DISPLAY INVISIBLE (-1200 1750);
FORCEPROP 1 LAST PATH I14
J 0
(-1150 1925);
DISPLAY 0.978723 (-1150 1925);
PAINT WHITE (-1150 1925);
DISPLAY INVISIBLE (-1150 1925);
FORCEPROP 1 LAST PART_NUMBER CS00001JE10
J 0
(-1160 1625);
DISPLAY 0.978723 (-1160 1625);
DISPLAY INVISIBLE (-1160 1625);
FORCEADD UNIVERSAL_GND..1
(-1200 1450);
FORCEPROP 3 LASTPIN (-1200 1500) SIG_NAME GND\g
J 0
(-1190 1510);
DISPLAY 0.659574 (-1190 1510);
PAINT MONO (-1190 1510);
DISPLAY INVISIBLE (-1190 1510);
FORCEPROP 2 LAST CDS_LIB pure_quanta_power
J 0
(-1200 1450);
DISPLAY INVISIBLE (-1200 1450);
FORCEPROP 1 LAST HDL_POWER GND
J 1
(-1175 1375);
DISPLAY 0.872340 (-1175 1375);
PAINT GREEN (-1175 1375);
DISPLAY INVISIBLE (-1175 1375);
FORCEPROP 1 LAST PATH I15
J 0
(-1125 1450);
DISPLAY 0.872340 (-1125 1450);
PAINT AQUA (-1125 1450);
DISPLAY INVISIBLE (-1125 1450);
FORCEADD UNIVERSAL_GND..1
(-975 2000);
FORCEPROP 3 LASTPIN (-975 2050) SIG_NAME GND\g
J 0
(-965 2060);
DISPLAY 0.659574 (-965 2060);
PAINT MONO (-965 2060);
DISPLAY INVISIBLE (-965 2060);
FORCEPROP 2 LAST CDS_LIB pure_quanta_power
J 0
(-975 2000);
DISPLAY INVISIBLE (-975 2000);
FORCEPROP 1 LAST HDL_POWER GND
J 1
(-950 1925);
DISPLAY 0.872340 (-950 1925);
PAINT GREEN (-950 1925);
DISPLAY INVISIBLE (-950 1925);
FORCEPROP 1 LAST PATH I16
J 0
(-900 2000);
DISPLAY 0.872340 (-900 2000);
PAINT AQUA (-900 2000);
DISPLAY INVISIBLE (-900 2000);
FORCEADD PT5161LRS..5
(-2325 3525);
FORCEPROP 1 LAST LOCATION U6013
J 0
(-2675 5850);
DISPLAY 0.723404 (-2675 5850);
PAINT SKYBLUE (-2675 5850);
FORCEPROP 0 LAST $SEC 5
J 0
(-2675 6000);
DISPLAY 0.680851 (-2675 6000);
PAINT MONO (-2675 6000);
DISPLAY INVISIBLE (-2675 6000);
FORCEPROP 0 LAST CDS_SEC 5
J 0
(-2675 6000);
DISPLAY 0.680851 (-2675 6000);
DISPLAY INVISIBLE (-2675 6000);
FORCEPROP 0 LASTPIN (-2825 5525) $PN AC13
J 2
(-2835 5535);
DISPLAY 0.680851 (-2835 5535);
PAINT MONO (-2835 5535);
FORCEPROP 0 LASTPIN (-2825 5475) $PN AC22
J 2
(-2835 5485);
DISPLAY 0.680851 (-2835 5485);
PAINT MONO (-2835 5485);
FORCEPROP 0 LASTPIN (-2825 5425) $PN AC32
J 2
(-2835 5435);
DISPLAY 0.680851 (-2835 5435);
PAINT MONO (-2835 5435);
FORCEPROP 0 LASTPIN (-2825 5375) $PN AC4
J 2
(-2835 5385);
DISPLAY 0.680851 (-2835 5385);
PAINT MONO (-2835 5385);
FORCEPROP 0 LASTPIN (-2825 5325) $PN AD2
J 2
(-2835 5335);
DISPLAY 0.680851 (-2835 5335);
PAINT MONO (-2835 5335);
FORCEPROP 0 LASTPIN (-2825 5275) $PN AD34
J 2
(-2835 5285);
DISPLAY 0.680851 (-2835 5285);
PAINT MONO (-2835 5285);
FORCEPROP 0 LASTPIN (-2825 5225) $PN AE1
J 2
(-2835 5235);
DISPLAY 0.680851 (-2835 5235);
PAINT MONO (-2835 5235);
FORCEPROP 0 LASTPIN (-2825 5175) $PN AE35
J 2
(-2835 5185);
DISPLAY 0.680851 (-2835 5185);
PAINT MONO (-2835 5185);
FORCEPROP 0 LASTPIN (-2825 5125) $PN AK13
J 2
(-2835 5135);
DISPLAY 0.680851 (-2835 5135);
PAINT MONO (-2835 5135);
FORCEPROP 0 LASTPIN (-2825 5075) $PN AK22
J 2
(-2835 5085);
DISPLAY 0.680851 (-2835 5085);
PAINT MONO (-2835 5085);
FORCEPROP 0 LASTPIN (-2825 5025) $PN AK32
J 2
(-2835 5035);
DISPLAY 0.680851 (-2835 5035);
PAINT MONO (-2835 5035);
FORCEPROP 0 LASTPIN (-2825 4975) $PN AK4
J 2
(-2835 4985);
DISPLAY 0.680851 (-2835 4985);
PAINT MONO (-2835 4985);
FORCEPROP 0 LASTPIN (-2825 4925) $PN AL2
J 2
(-2835 4935);
DISPLAY 0.680851 (-2835 4935);
PAINT MONO (-2835 4935);
FORCEPROP 0 LASTPIN (-2825 4875) $PN AL34
J 2
(-2835 4885);
DISPLAY 0.680851 (-2835 4885);
PAINT MONO (-2835 4885);
FORCEPROP 0 LASTPIN (-2825 4825) $PN AM1
J 2
(-2835 4835);
DISPLAY 0.680851 (-2835 4835);
PAINT MONO (-2835 4835);
FORCEPROP 0 LASTPIN (-2825 4775) $PN AM35
J 2
(-2835 4785);
DISPLAY 0.680851 (-2835 4785);
PAINT MONO (-2835 4785);
FORCEPROP 0 LASTPIN (-2825 4725) $PN AU13
J 2
(-2835 4735);
DISPLAY 0.680851 (-2835 4735);
PAINT MONO (-2835 4735);
FORCEPROP 0 LASTPIN (-2825 4675) $PN AU22
J 2
(-2835 4685);
DISPLAY 0.680851 (-2835 4685);
PAINT MONO (-2835 4685);
FORCEPROP 0 LASTPIN (-2825 4625) $PN AU32
J 2
(-2835 4635);
DISPLAY 0.680851 (-2835 4635);
PAINT MONO (-2835 4635);
FORCEPROP 0 LASTPIN (-2825 4575) $PN AU4
J 2
(-2835 4585);
DISPLAY 0.680851 (-2835 4585);
PAINT MONO (-2835 4585);
FORCEPROP 0 LASTPIN (-2825 4525) $PN AV2
J 2
(-2835 4535);
DISPLAY 0.680851 (-2835 4535);
PAINT MONO (-2835 4535);
FORCEPROP 0 LASTPIN (-2825 4475) $PN AV34
J 2
(-2835 4485);
DISPLAY 0.680851 (-2835 4485);
PAINT MONO (-2835 4485);
FORCEPROP 0 LASTPIN (-2825 4425) $PN AW1
J 2
(-2835 4435);
DISPLAY 0.680851 (-2835 4435);
PAINT MONO (-2835 4435);
FORCEPROP 0 LASTPIN (-2825 4375) $PN AW35
J 2
(-2835 4385);
DISPLAY 0.680851 (-2835 4385);
PAINT MONO (-2835 4385);
FORCEPROP 0 LASTPIN (-2825 4325) $PN B19
J 2
(-2835 4335);
DISPLAY 0.680851 (-2835 4335);
PAINT MONO (-2835 4335);
FORCEPROP 0 LASTPIN (-2825 4275) $PN BD13
J 2
(-2835 4285);
DISPLAY 0.680851 (-2835 4285);
PAINT MONO (-2835 4285);
FORCEPROP 0 LASTPIN (-2825 4225) $PN BD22
J 2
(-2835 4235);
DISPLAY 0.680851 (-2835 4235);
PAINT MONO (-2835 4235);
FORCEPROP 0 LASTPIN (-2825 4175) $PN BD32
J 2
(-2835 4185);
DISPLAY 0.680851 (-2835 4185);
PAINT MONO (-2835 4185);
FORCEPROP 0 LASTPIN (-2825 4125) $PN BD4
J 2
(-2835 4135);
DISPLAY 0.680851 (-2835 4135);
PAINT MONO (-2835 4135);
FORCEPROP 0 LASTPIN (-2825 4075) $PN BE2
J 2
(-2835 4085);
DISPLAY 0.680851 (-2835 4085);
PAINT MONO (-2835 4085);
FORCEPROP 0 LASTPIN (-2825 4025) $PN BE34
J 2
(-2835 4035);
DISPLAY 0.680851 (-2835 4035);
PAINT MONO (-2835 4035);
FORCEPROP 0 LASTPIN (-2825 3975) $PN BF1
J 2
(-2835 3985);
DISPLAY 0.680851 (-2835 3985);
PAINT MONO (-2835 3985);
FORCEPROP 0 LASTPIN (-2825 3925) $PN BF35
J 2
(-2835 3935);
DISPLAY 0.680851 (-2835 3935);
PAINT MONO (-2835 3935);
FORCEPROP 0 LASTPIN (-2825 3875) $PN BL13
J 2
(-2835 3885);
DISPLAY 0.680851 (-2835 3885);
PAINT MONO (-2835 3885);
FORCEPROP 0 LASTPIN (-2825 3825) $PN BL22
J 2
(-2835 3835);
DISPLAY 0.680851 (-2835 3835);
PAINT MONO (-2835 3835);
FORCEPROP 0 LASTPIN (-2825 3775) $PN BL32
J 2
(-2835 3785);
DISPLAY 0.680851 (-2835 3785);
PAINT MONO (-2835 3785);
FORCEPROP 0 LASTPIN (-2825 3725) $PN BL4
J 2
(-2835 3735);
DISPLAY 0.680851 (-2835 3735);
PAINT MONO (-2835 3735);
FORCEPROP 0 LASTPIN (-2825 3675) $PN BM2
J 2
(-2835 3685);
DISPLAY 0.680851 (-2835 3685);
PAINT MONO (-2835 3685);
FORCEPROP 0 LASTPIN (-2825 3625) $PN BM34
J 2
(-2835 3635);
DISPLAY 0.680851 (-2835 3635);
PAINT MONO (-2835 3635);
FORCEPROP 0 LASTPIN (-2825 3575) $PN BN1
J 2
(-2835 3585);
DISPLAY 0.680851 (-2835 3585);
PAINT MONO (-2835 3585);
FORCEPROP 0 LASTPIN (-2825 3525) $PN BN35
J 2
(-2835 3535);
DISPLAY 0.680851 (-2835 3535);
PAINT MONO (-2835 3535);
FORCEPROP 0 LASTPIN (-2825 3475) $PN BV13
J 2
(-2835 3485);
DISPLAY 0.680851 (-2835 3485);
PAINT MONO (-2835 3485);
FORCEPROP 0 LASTPIN (-2825 3425) $PN BV22
J 2
(-2835 3435);
DISPLAY 0.680851 (-2835 3435);
PAINT MONO (-2835 3435);
FORCEPROP 0 LASTPIN (-2825 3375) $PN BV32
J 2
(-2835 3385);
DISPLAY 0.680851 (-2835 3385);
PAINT MONO (-2835 3385);
FORCEPROP 0 LASTPIN (-2825 3325) $PN BV4
J 2
(-2835 3335);
DISPLAY 0.680851 (-2835 3335);
PAINT MONO (-2835 3335);
FORCEPROP 0 LASTPIN (-2825 3275) $PN BW2
J 2
(-2835 3285);
DISPLAY 0.680851 (-2835 3285);
PAINT MONO (-2835 3285);
FORCEPROP 0 LASTPIN (-2825 3225) $PN BW34
J 2
(-2835 3235);
DISPLAY 0.680851 (-2835 3235);
PAINT MONO (-2835 3235);
FORCEPROP 0 LASTPIN (-2825 3175) $PN BY1
J 2
(-2835 3185);
DISPLAY 0.680851 (-2835 3185);
PAINT MONO (-2835 3185);
FORCEPROP 0 LASTPIN (-2825 3125) $PN BY35
J 2
(-2835 3135);
DISPLAY 0.680851 (-2835 3135);
PAINT MONO (-2835 3135);
FORCEPROP 0 LASTPIN (-2825 3075) $PN CE13
J 2
(-2835 3085);
DISPLAY 0.680851 (-2835 3085);
PAINT MONO (-2835 3085);
FORCEPROP 0 LASTPIN (-2825 3025) $PN CE22
J 2
(-2835 3035);
DISPLAY 0.680851 (-2835 3035);
PAINT MONO (-2835 3035);
FORCEPROP 0 LASTPIN (-2825 2975) $PN CE32
J 2
(-2835 2985);
DISPLAY 0.680851 (-2835 2985);
PAINT MONO (-2835 2985);
FORCEPROP 0 LASTPIN (-2825 2925) $PN CE4
J 2
(-2835 2935);
DISPLAY 0.680851 (-2835 2935);
PAINT MONO (-2835 2935);
FORCEPROP 0 LASTPIN (-2825 2875) $PN CF2
J 2
(-2835 2885);
DISPLAY 0.680851 (-2835 2885);
PAINT MONO (-2835 2885);
FORCEPROP 0 LASTPIN (-2825 2825) $PN CF34
J 2
(-2835 2835);
DISPLAY 0.680851 (-2835 2835);
PAINT MONO (-2835 2835);
FORCEPROP 0 LASTPIN (-2825 2775) $PN CG1
J 2
(-2835 2785);
DISPLAY 0.680851 (-2835 2785);
PAINT MONO (-2835 2785);
FORCEPROP 0 LASTPIN (-2825 2725) $PN CG35
J 2
(-2835 2735);
DISPLAY 0.680851 (-2835 2735);
PAINT MONO (-2835 2735);
FORCEPROP 0 LASTPIN (-2825 2675) $PN CM13
J 2
(-2835 2685);
DISPLAY 0.680851 (-2835 2685);
PAINT MONO (-2835 2685);
FORCEPROP 0 LASTPIN (-2825 2625) $PN CM22
J 2
(-2835 2635);
DISPLAY 0.680851 (-2835 2635);
PAINT MONO (-2835 2635);
FORCEPROP 0 LASTPIN (-2825 2575) $PN CM32
J 2
(-2835 2585);
DISPLAY 0.680851 (-2835 2585);
PAINT MONO (-2835 2585);
FORCEPROP 0 LASTPIN (-2825 2525) $PN CM4
J 2
(-2835 2535);
DISPLAY 0.680851 (-2835 2535);
PAINT MONO (-2835 2535);
FORCEPROP 0 LASTPIN (-2825 2475) $PN CN2
J 2
(-2835 2485);
DISPLAY 0.680851 (-2835 2485);
PAINT MONO (-2835 2485);
FORCEPROP 0 LASTPIN (-2825 2425) $PN CN34
J 2
(-2835 2435);
DISPLAY 0.680851 (-2835 2435);
PAINT MONO (-2835 2435);
FORCEPROP 0 LASTPIN (-2825 2375) $PN CP1
J 2
(-2835 2385);
DISPLAY 0.680851 (-2835 2385);
PAINT MONO (-2835 2385);
FORCEPROP 0 LASTPIN (-2825 2325) $PN CP35
J 2
(-2835 2335);
DISPLAY 0.680851 (-2835 2335);
PAINT MONO (-2835 2335);
FORCEPROP 0 LASTPIN (-2825 2275) $PN CW13
J 2
(-2835 2285);
DISPLAY 0.680851 (-2835 2285);
PAINT MONO (-2835 2285);
FORCEPROP 0 LASTPIN (-2825 2225) $PN CW22
J 2
(-2835 2235);
DISPLAY 0.680851 (-2835 2235);
PAINT MONO (-2835 2235);
FORCEPROP 0 LASTPIN (-2825 2175) $PN CW32
J 2
(-2835 2185);
DISPLAY 0.680851 (-2835 2185);
PAINT MONO (-2835 2185);
FORCEPROP 0 LASTPIN (-2825 2125) $PN CW4
J 2
(-2835 2135);
DISPLAY 0.680851 (-2835 2135);
PAINT MONO (-2835 2135);
FORCEPROP 0 LASTPIN (-2825 2075) $PN CY2
J 2
(-2835 2085);
DISPLAY 0.680851 (-2835 2085);
PAINT MONO (-2835 2085);
FORCEPROP 0 LASTPIN (-2825 2025) $PN CY34
J 2
(-2835 2035);
DISPLAY 0.680851 (-2835 2035);
PAINT MONO (-2835 2035);
FORCEPROP 0 LASTPIN (-2825 1975) $PN DA1
J 2
(-2835 1985);
DISPLAY 0.680851 (-2835 1985);
PAINT MONO (-2835 1985);
FORCEPROP 0 LASTPIN (-2825 1925) $PN DA35
J 2
(-2835 1935);
DISPLAY 0.680851 (-2835 1935);
PAINT MONO (-2835 1935);
FORCEPROP 0 LASTPIN (-2825 1875) $PN DF13
J 2
(-2835 1885);
DISPLAY 0.680851 (-2835 1885);
PAINT MONO (-2835 1885);
FORCEPROP 0 LASTPIN (-2825 1825) $PN DF22
J 2
(-2835 1835);
DISPLAY 0.680851 (-2835 1835);
PAINT MONO (-2835 1835);
FORCEPROP 0 LASTPIN (-2825 1775) $PN DF32
J 2
(-2835 1785);
DISPLAY 0.680851 (-2835 1785);
PAINT MONO (-2835 1785);
FORCEPROP 0 LASTPIN (-2825 1725) $PN DF4
J 2
(-2835 1735);
DISPLAY 0.680851 (-2835 1735);
PAINT MONO (-2835 1735);
FORCEPROP 0 LASTPIN (-2825 1675) $PN DG2
J 2
(-2835 1685);
DISPLAY 0.680851 (-2835 1685);
PAINT MONO (-2835 1685);
FORCEPROP 0 LASTPIN (-2825 1625) $PN DG34
J 2
(-2835 1635);
DISPLAY 0.680851 (-2835 1635);
PAINT MONO (-2835 1635);
FORCEPROP 0 LASTPIN (-2825 1575) $PN DH1
J 2
(-2835 1585);
DISPLAY 0.680851 (-2835 1585);
PAINT MONO (-2835 1585);
FORCEPROP 0 LASTPIN (-2825 1525) $PN DH35
J 2
(-2835 1535);
DISPLAY 0.680851 (-2835 1535);
PAINT MONO (-2835 1535);
FORCEPROP 0 LASTPIN (-2825 1475) $PN DN13
J 2
(-2835 1485);
DISPLAY 0.680851 (-2835 1485);
PAINT MONO (-2835 1485);
FORCEPROP 0 LASTPIN (-1875 5525) $PN DN22
J 0
(-1865 5535);
DISPLAY 0.680851 (-1865 5535);
PAINT MONO (-1865 5535);
FORCEPROP 0 LASTPIN (-1875 5475) $PN DN32
J 0
(-1865 5485);
DISPLAY 0.680851 (-1865 5485);
PAINT MONO (-1865 5485);
FORCEPROP 0 LASTPIN (-1875 5425) $PN DN4
J 0
(-1865 5435);
DISPLAY 0.680851 (-1865 5435);
PAINT MONO (-1865 5435);
FORCEPROP 0 LASTPIN (-1875 5375) $PN DP2
J 0
(-1865 5385);
DISPLAY 0.680851 (-1865 5385);
PAINT MONO (-1865 5385);
FORCEPROP 0 LASTPIN (-1875 5325) $PN DP34
J 0
(-1865 5335);
DISPLAY 0.680851 (-1865 5335);
PAINT MONO (-1865 5335);
FORCEPROP 0 LASTPIN (-1875 5275) $PN DR1
J 0
(-1865 5285);
DISPLAY 0.680851 (-1865 5285);
PAINT MONO (-1865 5285);
FORCEPROP 0 LASTPIN (-1875 5225) $PN DR35
J 0
(-1865 5235);
DISPLAY 0.680851 (-1865 5235);
PAINT MONO (-1865 5235);
FORCEPROP 0 LASTPIN (-1875 5175) $PN DY13
J 0
(-1865 5185);
DISPLAY 0.680851 (-1865 5185);
PAINT MONO (-1865 5185);
FORCEPROP 0 LASTPIN (-1875 5125) $PN DY22
J 0
(-1865 5135);
DISPLAY 0.680851 (-1865 5135);
PAINT MONO (-1865 5135);
FORCEPROP 0 LASTPIN (-1875 5075) $PN DY32
J 0
(-1865 5085);
DISPLAY 0.680851 (-1865 5085);
PAINT MONO (-1865 5085);
FORCEPROP 0 LASTPIN (-1875 5025) $PN DY4
J 0
(-1865 5035);
DISPLAY 0.680851 (-1865 5035);
PAINT MONO (-1865 5035);
FORCEPROP 0 LASTPIN (-1875 4975) $PN E14
J 0
(-1865 4985);
DISPLAY 0.680851 (-1865 4985);
PAINT MONO (-1865 4985);
FORCEPROP 0 LASTPIN (-1875 4925) $PN E27
J 0
(-1865 4935);
DISPLAY 0.680851 (-1865 4935);
PAINT MONO (-1865 4935);
FORCEPROP 0 LASTPIN (-1875 4875) $PN E33
J 0
(-1865 4885);
DISPLAY 0.680851 (-1865 4885);
PAINT MONO (-1865 4885);
FORCEPROP 0 LASTPIN (-1875 4825) $PN EA2
J 0
(-1865 4835);
DISPLAY 0.680851 (-1865 4835);
PAINT MONO (-1865 4835);
FORCEPROP 0 LASTPIN (-1875 4775) $PN EA34
J 0
(-1865 4785);
DISPLAY 0.680851 (-1865 4785);
PAINT MONO (-1865 4785);
FORCEPROP 0 LASTPIN (-1875 4725) $PN EB1
J 0
(-1865 4735);
DISPLAY 0.680851 (-1865 4735);
PAINT MONO (-1865 4735);
FORCEPROP 0 LASTPIN (-1875 4675) $PN EB35
J 0
(-1865 4685);
DISPLAY 0.680851 (-1865 4685);
PAINT MONO (-1865 4685);
FORCEPROP 0 LASTPIN (-1875 4625) $PN EG13
J 0
(-1865 4635);
DISPLAY 0.680851 (-1865 4635);
PAINT MONO (-1865 4635);
FORCEPROP 0 LASTPIN (-1875 4575) $PN EG22
J 0
(-1865 4585);
DISPLAY 0.680851 (-1865 4585);
PAINT MONO (-1865 4585);
FORCEPROP 0 LASTPIN (-1875 4525) $PN EG32
J 0
(-1865 4535);
DISPLAY 0.680851 (-1865 4535);
PAINT MONO (-1865 4535);
FORCEPROP 0 LASTPIN (-1875 4475) $PN EG4
J 0
(-1865 4485);
DISPLAY 0.680851 (-1865 4485);
PAINT MONO (-1865 4485);
FORCEPROP 0 LASTPIN (-1875 4425) $PN EH2
J 0
(-1865 4435);
DISPLAY 0.680851 (-1865 4435);
PAINT MONO (-1865 4435);
FORCEPROP 0 LASTPIN (-1875 4375) $PN EH34
J 0
(-1865 4385);
DISPLAY 0.680851 (-1865 4385);
PAINT MONO (-1865 4385);
FORCEPROP 0 LASTPIN (-1875 4325) $PN EJ1
J 0
(-1865 4335);
DISPLAY 0.680851 (-1865 4335);
PAINT MONO (-1865 4335);
FORCEPROP 0 LASTPIN (-1875 4275) $PN EJ35
J 0
(-1865 4285);
DISPLAY 0.680851 (-1865 4285);
PAINT MONO (-1865 4285);
FORCEPROP 0 LASTPIN (-1875 4225) $PN EP13
J 0
(-1865 4235);
DISPLAY 0.680851 (-1865 4235);
PAINT MONO (-1865 4235);
FORCEPROP 0 LASTPIN (-1875 4175) $PN EP22
J 0
(-1865 4185);
DISPLAY 0.680851 (-1865 4185);
PAINT MONO (-1865 4185);
FORCEPROP 0 LASTPIN (-1875 4125) $PN EP32
J 0
(-1865 4135);
DISPLAY 0.680851 (-1865 4135);
PAINT MONO (-1865 4135);
FORCEPROP 0 LASTPIN (-1875 4075) $PN EP4
J 0
(-1865 4085);
DISPLAY 0.680851 (-1865 4085);
PAINT MONO (-1865 4085);
FORCEPROP 0 LASTPIN (-1875 4025) $PN ER2
J 0
(-1865 4035);
DISPLAY 0.680851 (-1865 4035);
PAINT MONO (-1865 4035);
FORCEPROP 0 LASTPIN (-1875 3975) $PN ER34
J 0
(-1865 3985);
DISPLAY 0.680851 (-1865 3985);
PAINT MONO (-1865 3985);
FORCEPROP 0 LASTPIN (-1875 3925) $PN ET1
J 0
(-1865 3935);
DISPLAY 0.680851 (-1865 3935);
PAINT MONO (-1865 3935);
FORCEPROP 0 LASTPIN (-1875 3875) $PN ET35
J 0
(-1865 3885);
DISPLAY 0.680851 (-1865 3885);
PAINT MONO (-1865 3885);
FORCEPROP 0 LASTPIN (-1875 3825) $PN FA15
J 0
(-1865 3835);
DISPLAY 0.680851 (-1865 3835);
PAINT MONO (-1865 3835);
FORCEPROP 0 LASTPIN (-1875 3775) $PN FA32
J 0
(-1865 3785);
DISPLAY 0.680851 (-1865 3785);
PAINT MONO (-1865 3785);
FORCEPROP 0 LASTPIN (-1875 3725) $PN FB2
J 0
(-1865 3735);
DISPLAY 0.680851 (-1865 3735);
PAINT MONO (-1865 3735);
FORCEPROP 0 LASTPIN (-1875 3675) $PN FB34
J 0
(-1865 3685);
DISPLAY 0.680851 (-1865 3685);
PAINT MONO (-1865 3685);
FORCEPROP 0 LASTPIN (-1875 3625) $PN FC19
J 0
(-1865 3635);
DISPLAY 0.680851 (-1865 3635);
PAINT MONO (-1865 3635);
FORCEPROP 0 LASTPIN (-1875 3575) $PN FC23
J 0
(-1865 3585);
DISPLAY 0.680851 (-1865 3585);
PAINT MONO (-1865 3585);
FORCEPROP 0 LASTPIN (-1875 3525) $PN FC25
J 0
(-1865 3535);
DISPLAY 0.680851 (-1865 3535);
PAINT MONO (-1865 3535);
FORCEPROP 0 LASTPIN (-1875 3475) $PN FC28
J 0
(-1865 3485);
DISPLAY 0.680851 (-1865 3485);
PAINT MONO (-1865 3485);
FORCEPROP 0 LASTPIN (-1875 3425) $PN FC3
J 0
(-1865 3435);
DISPLAY 0.680851 (-1865 3435);
PAINT MONO (-1865 3435);
FORCEPROP 0 LASTPIN (-1875 3375) $PN FC6
J 0
(-1865 3385);
DISPLAY 0.680851 (-1865 3385);
PAINT MONO (-1865 3385);
FORCEPROP 0 LASTPIN (-1875 3325) $PN FC9
J 0
(-1865 3335);
DISPLAY 0.680851 (-1865 3335);
PAINT MONO (-1865 3335);
FORCEPROP 0 LASTPIN (-1875 3275) $PN FD1
J 0
(-1865 3285);
DISPLAY 0.680851 (-1865 3285);
PAINT MONO (-1865 3285);
FORCEPROP 0 LASTPIN (-1875 3225) $PN FD35
J 0
(-1865 3235);
DISPLAY 0.680851 (-1865 3235);
PAINT MONO (-1865 3235);
FORCEPROP 0 LASTPIN (-1875 3175) $PN FF14
J 0
(-1865 3185);
DISPLAY 0.680851 (-1865 3185);
PAINT MONO (-1865 3185);
FORCEPROP 0 LASTPIN (-1875 3125) $PN FF21
J 0
(-1865 3135);
DISPLAY 0.680851 (-1865 3135);
PAINT MONO (-1865 3135);
FORCEPROP 0 LASTPIN (-1875 3075) $PN FJ12
J 0
(-1865 3085);
DISPLAY 0.680851 (-1865 3085);
PAINT MONO (-1865 3085);
FORCEPROP 0 LASTPIN (-1875 3025) $PN FJ19
J 0
(-1865 3035);
DISPLAY 0.680851 (-1865 3035);
PAINT MONO (-1865 3035);
FORCEPROP 0 LASTPIN (-1875 2975) $PN H12
J 0
(-1865 2985);
DISPLAY 0.680851 (-1865 2985);
PAINT MONO (-1865 2985);
FORCEPROP 0 LASTPIN (-1875 2925) $PN H16
J 0
(-1865 2935);
DISPLAY 0.680851 (-1865 2935);
PAINT MONO (-1865 2935);
FORCEPROP 0 LASTPIN (-1875 2875) $PN H19
J 0
(-1865 2885);
DISPLAY 0.680851 (-1865 2885);
PAINT MONO (-1865 2885);
FORCEPROP 0 LASTPIN (-1875 2825) $PN H31
J 0
(-1865 2835);
DISPLAY 0.680851 (-1865 2835);
PAINT MONO (-1865 2835);
FORCEPROP 0 LASTPIN (-1875 2775) $PN J22
J 0
(-1865 2785);
DISPLAY 0.680851 (-1865 2785);
PAINT MONO (-1865 2785);
FORCEPROP 0 LASTPIN (-1875 2725) $PN J4
J 0
(-1865 2735);
DISPLAY 0.680851 (-1865 2735);
PAINT MONO (-1865 2735);
FORCEPROP 0 LASTPIN (-1875 2675) $PN K2
J 0
(-1865 2685);
DISPLAY 0.680851 (-1865 2685);
PAINT MONO (-1865 2685);
FORCEPROP 0 LASTPIN (-1875 2625) $PN K34
J 0
(-1865 2635);
DISPLAY 0.680851 (-1865 2635);
PAINT MONO (-1865 2635);
FORCEPROP 0 LASTPIN (-1875 2575) $PN L1
J 0
(-1865 2585);
DISPLAY 0.680851 (-1865 2585);
PAINT MONO (-1865 2585);
FORCEPROP 0 LASTPIN (-1875 2525) $PN L35
J 0
(-1865 2535);
DISPLAY 0.680851 (-1865 2535);
PAINT MONO (-1865 2535);
FORCEPROP 0 LASTPIN (-1875 2475) $PN T13
J 0
(-1865 2485);
DISPLAY 0.680851 (-1865 2485);
PAINT MONO (-1865 2485);
FORCEPROP 0 LASTPIN (-1875 2425) $PN T22
J 0
(-1865 2435);
DISPLAY 0.680851 (-1865 2435);
PAINT MONO (-1865 2435);
FORCEPROP 0 LASTPIN (-1875 2375) $PN T32
J 0
(-1865 2385);
DISPLAY 0.680851 (-1865 2385);
PAINT MONO (-1865 2385);
FORCEPROP 0 LASTPIN (-1875 2325) $PN T4
J 0
(-1865 2335);
DISPLAY 0.680851 (-1865 2335);
PAINT MONO (-1865 2335);
FORCEPROP 0 LASTPIN (-1875 2275) $PN U2
J 0
(-1865 2285);
DISPLAY 0.680851 (-1865 2285);
PAINT MONO (-1865 2285);
FORCEPROP 0 LASTPIN (-1875 2225) $PN U34
J 0
(-1865 2235);
DISPLAY 0.680851 (-1865 2235);
PAINT MONO (-1865 2235);
FORCEPROP 0 LASTPIN (-1875 2175) $PN V1
J 0
(-1865 2185);
DISPLAY 0.680851 (-1865 2185);
PAINT MONO (-1865 2185);
FORCEPROP 0 LASTPIN (-1875 2125) $PN V35
J 0
(-1865 2135);
DISPLAY 0.680851 (-1865 2135);
PAINT MONO (-1865 2135);
FORCEPROP 0 LASTPIN (-1875 2025) $PN A1
J 0
(-1865 2035);
DISPLAY 0.680851 (-1865 2035);
PAINT MONO (-1865 2035);
FORCEPROP 0 LASTPIN (-1875 1975) $PN A35
J 0
(-1865 1985);
DISPLAY 0.680851 (-1865 1985);
PAINT MONO (-1865 1985);
FORCEPROP 0 LASTPIN (-1875 1925) $PN C2
J 0
(-1865 1935);
DISPLAY 0.680851 (-1865 1935);
PAINT MONO (-1865 1935);
FORCEPROP 0 LASTPIN (-1875 1875) $PN C34
J 0
(-1865 1885);
DISPLAY 0.680851 (-1865 1885);
PAINT MONO (-1865 1885);
FORCEPROP 0 LASTPIN (-1875 1825) $PN D1
J 0
(-1865 1835);
DISPLAY 0.680851 (-1865 1835);
PAINT MONO (-1865 1835);
FORCEPROP 0 LASTPIN (-1875 1775) $PN D35
J 0
(-1865 1785);
DISPLAY 0.680851 (-1865 1785);
PAINT MONO (-1865 1785);
FORCEPROP 0 LASTPIN (-1875 1725) $PN FE2
J 0
(-1865 1735);
DISPLAY 0.680851 (-1865 1735);
PAINT MONO (-1865 1735);
FORCEPROP 0 LASTPIN (-1875 1675) $PN FE34
J 0
(-1865 1685);
DISPLAY 0.680851 (-1865 1685);
PAINT MONO (-1865 1685);
FORCEPROP 0 LASTPIN (-1875 1625) $PN FG1
J 0
(-1865 1635);
DISPLAY 0.680851 (-1865 1635);
PAINT MONO (-1865 1635);
FORCEPROP 0 LASTPIN (-1875 1575) $PN FG35
J 0
(-1865 1585);
DISPLAY 0.680851 (-1865 1585);
PAINT MONO (-1865 1585);
FORCEPROP 0 LASTPIN (-1875 1525) $PN FH2
J 0
(-1865 1535);
DISPLAY 0.680851 (-1865 1535);
PAINT MONO (-1865 1535);
FORCEPROP 0 LASTPIN (-1875 1475) $PN FH34
J 0
(-1865 1485);
DISPLAY 0.680851 (-1865 1485);
PAINT MONO (-1865 1485);
FORCEPROP 2 LAST PART_TYPE SMLF
J 0
(-2675 5950);
DISPLAY 0.680851 (-2675 5950);
FORCEPROP 2 LAST VALUE PT5161LRS
J 0
(-2675 5900);
DISPLAY 0.680851 (-2675 5900);
FORCEPROP 1 LAST MATERIAL IC
J 0
(-2675 5700);
DISPLAY 0.723404 (-2675 5700);
PAINT GREEN (-2675 5700);
FORCEPROP 1 LAST NEEDS_NO_SIZE TRUE
J 0
(-2325 3525);
DISPLAY 0.723404 (-2325 3525);
PAINT GREEN (-2325 3525);
DISPLAY INVISIBLE (-2325 3525);
FORCEPROP 1 LAST CDS_LMAN_SYM_OUTLINE -350,2150,300,-2150
J 0
(-2325 3525);
DISPLAY 0.468085 (-2325 3525);
PAINT GREEN (-2325 3525);
DISPLAY INVISIBLE (-2325 3525);
FORCEPROP 2 LAST CDS_LIB pure_quanta
J 0
(-2325 3525);
DISPLAY INVISIBLE (-2325 3525);
FORCEPROP 1 LAST PATH I17
J 0
(-2325 3525);
DISPLAY 0.723404 (-2325 3525);
PAINT GREEN (-2325 3525);
DISPLAY INVISIBLE (-2325 3525);
FORCEPROP 1 LAST PART_NUMBER AJ051610U03
J 0
(-2675 5775);
DISPLAY 0.723404 (-2675 5775);
PAINT GREEN (-2675 5775);
DISPLAY INVISIBLE (-2675 5775);
FORCEADD Q_RES..2
(-7550 3300);
FORCEPROP 1 LAST LOCATION R1124
J 0
(-7505 3425);
DISPLAY 0.978723 (-7505 3425);
PAINT WHITE (-7505 3425);
FORCEPROP 0 LAST $SEC 1
J 0
(-7500 3475);
DISPLAY 0.680851 (-7500 3475);
PAINT MONO (-7500 3475);
DISPLAY INVISIBLE (-7500 3475);
FORCEPROP 0 LAST CDS_SEC 1
J 0
(-7500 3475);
DISPLAY 0.680851 (-7500 3475);
DISPLAY INVISIBLE (-7500 3475);
FORCEPROP 1 LASTPIN (-7550 3400) $PN 1
J 0
(-7545 3362);
DISPLAY 0.787234 (-7545 3362);
PAINT MONO (-7545 3362);
FORCEPROP 1 LASTPIN (-7550 3200) $PN 2
J 0
(-7545 3210);
DISPLAY 0.787234 (-7545 3210);
PAINT MONO (-7545 3210);
FORCEPROP 1 LAST VALUE 200
J 0
(-7505 3375);
DISPLAY 0.978723 (-7505 3375);
FORCEPROP 1 LAST TOLERANCE 1%
J 0
(-7505 3325);
DISPLAY 0.978723 (-7505 3325);
FORCEPROP 1 LAST MATERIAL CHIP
J 0
(-7510 3225);
DISPLAY 0.978723 (-7510 3225);
FORCEPROP 1 LAST PACK_TYPE 0201LF
J 0
(-7510 3125);
DISPLAY 0.978723 (-7510 3125);
FORCEPROP 1 LAST WATTAGE 1/20W
J 0
(-7510 3275);
DISPLAY 0.978723 (-7510 3275);
FORCEPROP 2 LAST CDS_LIB pure_quanta
J 0
(-7550 3300);
DISPLAY INVISIBLE (-7550 3300);
FORCEPROP 1 LAST PATH I18
J 0
(-7500 3475);
DISPLAY 0.978723 (-7500 3475);
PAINT WHITE (-7500 3475);
DISPLAY INVISIBLE (-7500 3475);
FORCEPROP 1 LAST PART_NUMBER CS12001FE12
J 0
(-7510 3175);
DISPLAY 0.978723 (-7510 3175);
DISPLAY INVISIBLE (-7510 3175);
FORCEADD Q_RES..2
(-8575 3850);
FORCEPROP 1 LAST LOCATION R1123
J 0
(-8530 3975);
DISPLAY 0.787234 (-8530 3975);
PAINT SKYBLUE (-8530 3975);
FORCEPROP 0 LAST $SEC 1
J 0
(-8525 4025);
DISPLAY 0.680851 (-8525 4025);
PAINT MONO (-8525 4025);
DISPLAY INVISIBLE (-8525 4025);
FORCEPROP 0 LAST CDS_SEC 1
J 0
(-8525 4025);
DISPLAY 0.680851 (-8525 4025);
DISPLAY INVISIBLE (-8525 4025);
FORCEPROP 1 LASTPIN (-8575 3950) $PN 1
J 0
(-8570 3912);
DISPLAY 0.787234 (-8570 3912);
PAINT MONO (-8570 3912);
FORCEPROP 1 LASTPIN (-8575 3750) $PN 2
J 0
(-8570 3760);
DISPLAY 0.787234 (-8570 3760);
PAINT MONO (-8570 3760);
FORCEPROP 1 LAST VALUE 1K
J 0
(-8530 3925);
DISPLAY 0.787234 (-8530 3925);
FORCEPROP 1 LAST TOLERANCE 1%
J 0
(-8530 3875);
DISPLAY 0.787234 (-8530 3875);
FORCEPROP 1 LAST WATTAGE 1/20W
J 0
(-8535 3825);
DISPLAY 0.787234 (-8535 3825);
FORCEPROP 1 LAST MATERIAL EMPTY
J 0
(-8535 3775);
DISPLAY 0.787234 (-8535 3775);
PAINT RED (-8535 3775);
FORCEPROP 1 LAST PACK_TYPE 0201LF
J 0
(-8535 3675);
DISPLAY 0.787234 (-8535 3675);
FORCEPROP 2 LAST CDS_LIB pure_quanta
J 0
(-8575 3850);
DISPLAY INVISIBLE (-8575 3850);
FORCEPROP 1 LAST PATH I19
J 0
(-8525 4025);
DISPLAY 0.978723 (-8525 4025);
PAINT WHITE (-8525 4025);
DISPLAY INVISIBLE (-8525 4025);
FORCEPROP 1 LAST PART_NUMBER CS21001FE07
J 0
(-8535 3725);
DISPLAY 0.978723 (-8535 3725);
DISPLAY INVISIBLE (-8535 3725);
FORCEADD P1V0..1
(-8250 4350);
FORCEPROP 3 LASTPIN (-8250 4300) SIG_NAME P1V8_CPU0_RT3_1A_1D\g
J 0
(-8240 4310);
DISPLAY 0.659574 (-8240 4310);
PAINT MONO (-8240 4310);
DISPLAY INVISIBLE (-8240 4310);
FORCEPROP 1 LAST HDL_POWER P1V8_CPU0_RT3_1A_1D
J 1
(-8250 4400);
DISPLAY 0.489362 (-8250 4400);
PAINT SKYBLUE (-8250 4400);
FORCEPROP 2 LAST CDS_LIB pure_quanta_power
J 0
(-8250 4350);
DISPLAY INVISIBLE (-8250 4350);
FORCEPROP 1 LAST PATH I3
J 0
(-8200 4375);
DISPLAY 0.872340 (-8200 4375);
PAINT AQUA (-8200 4375);
DISPLAY INVISIBLE (-8200 4375);
FORCEADD UNIVERSAL_GND..1
(-7550 3050);
FORCEPROP 3 LASTPIN (-7550 3100) SIG_NAME GND\g
J 0
(-7540 3110);
DISPLAY 0.659574 (-7540 3110);
PAINT MONO (-7540 3110);
DISPLAY INVISIBLE (-7540 3110);
FORCEPROP 2 LAST CDS_LIB pure_quanta_power
J 0
(-7550 3050);
DISPLAY INVISIBLE (-7550 3050);
FORCEPROP 1 LAST HDL_POWER GND
J 1
(-7525 2975);
DISPLAY 0.872340 (-7525 2975);
PAINT GREEN (-7525 2975);
DISPLAY INVISIBLE (-7525 2975);
FORCEPROP 1 LAST PATH I4
J 0
(-7475 3050);
DISPLAY 0.872340 (-7475 3050);
PAINT AQUA (-7475 3050);
DISPLAY INVISIBLE (-7475 3050);
FORCEADD PT5161LRS..4
(-6400 4100);
FORCEPROP 1 LAST LOCATION U6013
J 0
(-6850 5025);
DISPLAY 0.723404 (-6850 5025);
PAINT SKYBLUE (-6850 5025);
FORCEPROP 0 LAST $SEC 4
J 0
(-6850 5175);
DISPLAY 0.680851 (-6850 5175);
PAINT MONO (-6850 5175);
DISPLAY INVISIBLE (-6850 5175);
FORCEPROP 0 LAST CDS_SEC 4
J 0
(-6850 5175);
DISPLAY 0.680851 (-6850 5175);
DISPLAY INVISIBLE (-6850 5175);
FORCEPROP 0 LASTPIN (-7000 4700) $PN BV20
J 2
(-7010 4710);
DISPLAY 0.680851 (-7010 4710);
PAINT MONO (-7010 4710);
FORCEPROP 0 LASTPIN (-7000 4650) $PN CE17
J 2
(-7010 4660);
DISPLAY 0.680851 (-7010 4660);
PAINT MONO (-7010 4660);
FORCEPROP 0 LASTPIN (-7000 4600) $PN CE20
J 2
(-7010 4610);
DISPLAY 0.680851 (-7010 4610);
PAINT MONO (-7010 4610);
FORCEPROP 0 LASTPIN (-7000 4550) $PN CM17
J 2
(-7010 4560);
DISPLAY 0.680851 (-7010 4560);
PAINT MONO (-7010 4560);
FORCEPROP 0 LASTPIN (-7000 4500) $PN CM20
J 2
(-7010 4510);
DISPLAY 0.680851 (-7010 4510);
PAINT MONO (-7010 4510);
FORCEPROP 0 LASTPIN (-7000 4050) $PN BV17
J 2
(-7010 4060);
DISPLAY 0.680851 (-7010 4060);
PAINT MONO (-7010 4060);
FORCEPROP 0 LASTPIN (-5850 4700) $PN AC17
J 0
(-5840 4710);
DISPLAY 0.680851 (-5840 4710);
PAINT MONO (-5840 4710);
FORCEPROP 0 LASTPIN (-5850 4650) $PN AC20
J 0
(-5840 4660);
DISPLAY 0.680851 (-5840 4660);
PAINT MONO (-5840 4660);
FORCEPROP 0 LASTPIN (-5850 4600) $PN AK17
J 0
(-5840 4610);
DISPLAY 0.680851 (-5840 4610);
PAINT MONO (-5840 4610);
FORCEPROP 0 LASTPIN (-5850 4550) $PN AK20
J 0
(-5840 4560);
DISPLAY 0.680851 (-5840 4560);
PAINT MONO (-5840 4560);
FORCEPROP 0 LASTPIN (-5850 4500) $PN AU17
J 0
(-5840 4510);
DISPLAY 0.680851 (-5840 4510);
PAINT MONO (-5840 4510);
FORCEPROP 0 LASTPIN (-5850 4450) $PN AU20
J 0
(-5840 4460);
DISPLAY 0.680851 (-5840 4460);
PAINT MONO (-5840 4460);
FORCEPROP 0 LASTPIN (-5850 4400) $PN BD17
J 0
(-5840 4410);
DISPLAY 0.680851 (-5840 4410);
PAINT MONO (-5840 4410);
FORCEPROP 0 LASTPIN (-5850 4350) $PN BD20
J 0
(-5840 4360);
DISPLAY 0.680851 (-5840 4360);
PAINT MONO (-5840 4360);
FORCEPROP 0 LASTPIN (-5850 4300) $PN DF17
J 0
(-5840 4310);
DISPLAY 0.680851 (-5840 4310);
PAINT MONO (-5840 4310);
FORCEPROP 0 LASTPIN (-5850 4250) $PN DF20
J 0
(-5840 4260);
DISPLAY 0.680851 (-5840 4260);
PAINT MONO (-5840 4260);
FORCEPROP 0 LASTPIN (-5850 4200) $PN DN17
J 0
(-5840 4210);
DISPLAY 0.680851 (-5840 4210);
PAINT MONO (-5840 4210);
FORCEPROP 0 LASTPIN (-5850 4150) $PN DN20
J 0
(-5840 4160);
DISPLAY 0.680851 (-5840 4160);
PAINT MONO (-5840 4160);
FORCEPROP 0 LASTPIN (-5850 4100) $PN DY17
J 0
(-5840 4110);
DISPLAY 0.680851 (-5840 4110);
PAINT MONO (-5840 4110);
FORCEPROP 0 LASTPIN (-5850 4050) $PN DY20
J 0
(-5840 4060);
DISPLAY 0.680851 (-5840 4060);
PAINT MONO (-5840 4060);
FORCEPROP 0 LASTPIN (-5850 4000) $PN EG17
J 0
(-5840 4010);
DISPLAY 0.680851 (-5840 4010);
PAINT MONO (-5840 4010);
FORCEPROP 0 LASTPIN (-5850 3950) $PN EG20
J 0
(-5840 3960);
DISPLAY 0.680851 (-5840 3960);
PAINT MONO (-5840 3960);
FORCEPROP 0 LASTPIN (-5850 3900) $PN EP17
J 0
(-5840 3910);
DISPLAY 0.680851 (-5840 3910);
PAINT MONO (-5840 3910);
FORCEPROP 0 LASTPIN (-5850 3850) $PN EP20
J 0
(-5840 3860);
DISPLAY 0.680851 (-5840 3860);
PAINT MONO (-5840 3860);
FORCEPROP 0 LASTPIN (-5850 3800) $PN T17
J 0
(-5840 3810);
DISPLAY 0.680851 (-5840 3810);
PAINT MONO (-5840 3810);
FORCEPROP 0 LASTPIN (-5850 3750) $PN T20
J 0
(-5840 3760);
DISPLAY 0.680851 (-5840 3760);
PAINT MONO (-5840 3760);
FORCEPROP 0 LASTPIN (-5850 3600) $PN BL17
J 0
(-5840 3610);
DISPLAY 0.680851 (-5840 3610);
PAINT MONO (-5840 3610);
FORCEPROP 0 LASTPIN (-5850 3550) $PN BL20
J 0
(-5840 3560);
DISPLAY 0.680851 (-5840 3560);
PAINT MONO (-5840 3560);
FORCEPROP 0 LASTPIN (-5850 3500) $PN CW17
J 0
(-5840 3510);
DISPLAY 0.680851 (-5840 3510);
PAINT MONO (-5840 3510);
FORCEPROP 0 LASTPIN (-5850 3450) $PN CW20
J 0
(-5840 3460);
DISPLAY 0.680851 (-5840 3460);
PAINT MONO (-5840 3460);
FORCEPROP 0 LASTPIN (-7000 3600) $PN G1
J 2
(-7010 3610);
DISPLAY 0.680851 (-7010 3610);
PAINT MONO (-7010 3610);
FORCEPROP 2 LAST VALUE PT5161LRS
J 0
(-6850 5075);
DISPLAY 0.680851 (-6850 5075);
FORCEPROP 2 LAST PART_TYPE SMLF
J 0
(-6850 5125);
DISPLAY 0.680851 (-6850 5125);
FORCEPROP 1 LAST MATERIAL IC
J 0
(-6850 4875);
DISPLAY 0.723404 (-6850 4875);
PAINT GREEN (-6850 4875);
FORCEPROP 1 LAST NEEDS_NO_SIZE TRUE
J 0
(-6400 4100);
DISPLAY 0.723404 (-6400 4100);
PAINT GREEN (-6400 4100);
DISPLAY INVISIBLE (-6400 4100);
FORCEPROP 1 LAST CDS_LMAN_SYM_OUTLINE -450,750,400,-750
J 0
(-6400 4100);
DISPLAY 0.468085 (-6400 4100);
PAINT GREEN (-6400 4100);
DISPLAY INVISIBLE (-6400 4100);
FORCEPROP 2 LAST CDS_LIB pure_quanta
J 0
(-6400 4100);
DISPLAY INVISIBLE (-6400 4100);
FORCEPROP 1 LAST PATH I6
J 0
(-6400 4100);
DISPLAY 0.723404 (-6400 4100);
PAINT GREEN (-6400 4100);
DISPLAY INVISIBLE (-6400 4100);
FORCEPROP 1 LAST PART_NUMBER AJ051610U03
J 0
(-6850 4950);
DISPLAY 0.723404 (-6850 4950);
PAINT GREEN (-6850 4950);
DISPLAY INVISIBLE (-6850 4950);
FORCEADD P1V0..1
(-4550 3750);
FORCEPROP 3 LASTPIN (-4550 3700) SIG_NAME P0V9_CPU0_RT_2D\g
J 0
(-4540 3710);
DISPLAY 0.659574 (-4540 3710);
PAINT MONO (-4540 3710);
DISPLAY INVISIBLE (-4540 3710);
FORCEPROP 1 LAST HDL_POWER P0V9_CPU0_RT_2D
J 1
(-4550 3800);
DISPLAY 0.489362 (-4550 3800);
PAINT SKYBLUE (-4550 3800);
FORCEPROP 2 LAST CDS_LIB pure_quanta_power
J 0
(-4550 3750);
DISPLAY INVISIBLE (-4550 3750);
FORCEPROP 1 LAST PATH I7
J 0
(-4500 3775);
DISPLAY 0.872340 (-4500 3775);
PAINT AQUA (-4500 3775);
DISPLAY INVISIBLE (-4500 3775);
FORCEADD P1V0..1
(-7675 4800);
FORCEPROP 3 LASTPIN (-7675 4750) SIG_NAME P1V8_CPU0_RT3_1A\g
J 0
(-7665 4760);
DISPLAY 0.659574 (-7665 4760);
PAINT MONO (-7665 4760);
DISPLAY INVISIBLE (-7665 4760);
FORCEPROP 1 LAST HDL_POWER P1V8_CPU0_RT3_1A
J 1
(-7675 4850);
DISPLAY 0.489362 (-7675 4850);
PAINT SKYBLUE (-7675 4850);
FORCEPROP 2 LAST CDS_LIB pure_quanta_power
J 0
(-7675 4800);
DISPLAY INVISIBLE (-7675 4800);
FORCEPROP 1 LAST PATH I8
J 0
(-7625 4825);
DISPLAY 0.872340 (-7625 4825);
PAINT AQUA (-7625 4825);
DISPLAY INVISIBLE (-7625 4825);
FORCEADD VCC_CORE..1
(-5150 4500);
FORCEPROP 3 LASTPIN (-5150 4450) SIG_NAME P0V9_CPU0_RT3_2A_2D\g
J 0
(-5140 4460);
DISPLAY 0.659574 (-5140 4460);
PAINT MONO (-5140 4460);
DISPLAY INVISIBLE (-5140 4460);
FORCEPROP 1 LAST HDL_POWER P0V9_CPU0_RT3_2A_2D
J 1
(-5150 4550);
DISPLAY 0.617021 (-5150 4550);
PAINT SKYBLUE (-5150 4550);
FORCEPROP 2 LAST CDS_LIB pure_quanta_power
J 0
(-5150 4500);
DISPLAY INVISIBLE (-5150 4500);
FORCEPROP 1 LAST PATH I9
J 0
(-5100 4525);
DISPLAY 0.872340 (-5100 4525);
PAINT AQUA (-5100 4525);
DISPLAY INVISIBLE (-5100 4525);
FORCEADD DNS..2
(-8500 3850);
PAINT RED (-8500 3850);
FORCEPROP 2 LAST CDS_LIB mstr_misc
J 0
(-8500 3850);
DISPLAY INVISIBLE (-8500 3850);
FORCEPROP 1 LAST COMMENT_BODY TRUE
J 0
(-8500 3850);
DISPLAY INVISIBLE (-8500 3850);
FORCEADD QUANTA_TITLE_BLOCK_C..1
(0 0);
FORCEPROP 0 LAST CDS_CON_LAST_MODIFIED Thu Sep 14 16:13:09 2023
J 0
(-1885 15);
DISPLAY INVISIBLE (-1885 15);
FORCEPROP 1 LAST CUSTOM_TXT_CDS <CON_LAST_MODIFIED>
J 0
(-1885 15);
DISPLAY 0.978723 (-1885 15);
FORCEPROP 2 LAST CUSTOM_TXT_CDS <XR_PAGE_TITLE>
J 0
(-7890 5250);
DISPLAY 0.638298 (-7890 5250);
PAINT PINK (-7890 5250);
DISPLAY INVISIBLE (-7890 5250);
FORCEPROP 1 LAST CUSTOM_TXT_CDS <NAME_2>
J 0
(-3175 50);
FORCEPROP 1 LAST CUSTOM_TXT_CDS <NAME_1>
J 0
(-3175 175);
FORCEPROP 1 LAST CUSTOM_TXT_CDS <Q_NUMBER>
J 0
(-1403 103);
DISPLAY 1.212766 (-1403 103);
FORCEPROP 1 LAST CUSTOM_TXT_CDS <Q_PROJ>
J 0
(-2382 102);
DISPLAY 1.212766 (-2382 102);
FORCEPROP 1 LAST CUSTOM_TXT_CDS <Q_REV>
J 0
(-184 103);
DISPLAY 1.212766 (-184 103);
FORCEPROP 1 LAST CUSTOM_TXT_CDS <CON_PAGE_NUM> OF <CON_TOTAL_PAGES>
J 0
(-446 18);
DISPLAY 0.978723 (-446 18);
FORCEPROP 1 LAST Q_TITLE RETIMER_CPU0_P3 POWER(6)
J 0
(-9366 26);
DISPLAY 2.446809 (-9366 26);
PAINT GREEN (-9366 26);
FORCEPROP 2 LAST CDS_LIB pure_quanta
J 0
(0 0);
DISPLAY INVISIBLE (0 0);
FORCEPROP 1 LAST CDS_LMAN_SYM_OUTLINE -9475,6775,100,-125
J 0
(0 0);
DISPLAY 0.468085 (0 0);
PAINT GREEN (0 0);
DISPLAY INVISIBLE (0 0);
FORCEPROP 2 LAST PAGE_BORDER TRUE
J 0
(-7890 5250);
DISPLAY 0.638298 (-7890 5250);
PAINT PINK (-7890 5250);
DISPLAY INVISIBLE (-7890 5250);
FORCEPROP 2 LAST CDS_XR_PAGE_TITLE CR-311 : @T6G_MB_LIB.T6G(SCH_1):PAGE311
J 0
(-7890 5250);
DISPLAY 0.638298 (-7890 5250);
PAINT PINK (-7890 5250);
DISPLAY INVISIBLE (-7890 5250);
FORCEPROP 1 LAST Q_DEPT BU9
J 1
(-3763 49);
DISPLAY 1.957447 (-3763 49);
PAINT GREEN (-3763 49);
DISPLAY INVISIBLE (-3763 49);
FORCEPROP 1 LAST COMMENT_BODY TRUE
J 0
(12 -13);
DISPLAY 0.978723 (12 -13);
PAINT GREEN (12 -13);
DISPLAY INVISIBLE (12 -13);
WIRE 16 -1 (-8575 4025)(-8575 3950);
WIRE 16 -1 (-1350 1100)(-1350 950);
WIRE 16 -1 (-1200 1650)(-1200 1500);
WIRE 16 -1 (-7550 3200)(-7550 3100);
WIRE 16 -1 (-5850 4400)(-5600 4400);
WIRE 16 -1 (-5600 4400)(-5150 4400);
WIRE 16 -1 (-5600 4400)(-5600 4350);
WIRE 16 -1 (-5600 4350)(-5600 4300);
WIRE 16 -1 (-5850 4350)(-5600 4350);
WIRE 16 -1 (-5150 4400)(-5150 4450);
WIRE 16 -1 (-5600 4300)(-5600 4250);
WIRE 16 -1 (-5600 4300)(-5850 4300);
WIRE 16 -1 (-5600 4250)(-5850 4250);
WIRE 16 -1 (-7000 4700)(-7425 4700);
WIRE 16 -1 (-7425 4700)(-7425 4650);
WIRE 16 -1 (-7425 4700)(-7675 4700);
WIRE 16 -1 (-7675 4700)(-7675 4750);
WIRE 16 -1 (-7000 4650)(-7425 4650);
WIRE 16 -1 (-7425 4650)(-7425 4600);
WIRE 16 -1 (-7000 4600)(-7425 4600);
WIRE 16 -1 (-7425 4600)(-7425 4550);
WIRE 16 -1 (-7000 4550)(-7425 4550);
WIRE 16 -1 (-7425 4550)(-7425 4500);
WIRE 16 -1 (-7425 4500)(-7000 4500);
WIRE 16 -1 (-5600 3850)(-5600 3800);
WIRE 16 -1 (-5600 3900)(-5600 3850);
WIRE 16 -1 (-5850 3850)(-5600 3850);
WIRE 16 -1 (-5600 3800)(-5600 3750);
WIRE 16 -1 (-5850 3800)(-5600 3800);
WIRE 16 -1 (-5600 3750)(-5850 3750);
WIRE 16 -1 (-5600 3950)(-5600 3900);
WIRE 16 -1 (-5850 3900)(-5600 3900);
WIRE 16 -1 (-5600 4000)(-5600 3950);
WIRE 16 -1 (-5850 3950)(-5600 3950);
WIRE 16 -1 (-5600 4050)(-5600 4000);
WIRE 16 -1 (-5850 4000)(-5600 4000);
WIRE 16 -1 (-5600 4100)(-5600 4050);
WIRE 16 -1 (-5850 4050)(-5600 4050);
WIRE 16 -1 (-5600 4150)(-5600 4100);
WIRE 16 -1 (-5850 4100)(-5600 4100);
WIRE 16 -1 (-5600 4200)(-5600 4150);
WIRE 16 -1 (-5850 4150)(-5600 4150);
WIRE 16 -1 (-5600 4200)(-4575 4200);
WIRE 16 -1 (-5600 4200)(-5850 4200);
WIRE 16 -1 (-4575 4700)(-4575 4200);
WIRE 16 -1 (-5625 4700)(-4575 4700);
WIRE 16 -1 (-4575 4700)(-4575 4925);
WIRE 16 -1 (-5850 4700)(-5625 4700);
WIRE 16 -1 (-5625 4700)(-5625 4650);
WIRE 16 -1 (-5625 4650)(-5625 4600);
WIRE 16 -1 (-5850 4650)(-5625 4650);
WIRE 16 -1 (-5625 4600)(-5625 4550);
WIRE 16 -1 (-5850 4600)(-5625 4600);
WIRE 16 -1 (-5625 4550)(-5625 4500);
WIRE 16 -1 (-5850 4550)(-5625 4550);
WIRE 16 -1 (-5625 4500)(-5625 4450);
WIRE 16 -1 (-5850 4500)(-5625 4500);
WIRE 16 -1 (-5625 4450)(-5850 4450);
WIRE 16 -1 (-2825 5525)(-3025 5525);
WIRE 16 -1 (-3025 5525)(-3025 5475);
WIRE 16 -1 (-2825 5475)(-3025 5475);
WIRE 16 -1 (-3025 5475)(-3025 5425);
WIRE 16 -1 (-2825 5425)(-3025 5425);
WIRE 16 -1 (-3025 5425)(-3025 5375);
WIRE 16 -1 (-2825 5375)(-3025 5375);
WIRE 16 -1 (-3025 5375)(-3025 5325);
WIRE 16 -1 (-2825 5325)(-3025 5325);
WIRE 16 -1 (-3025 5325)(-3025 5275);
WIRE 16 -1 (-2825 5275)(-3025 5275);
WIRE 16 -1 (-3025 5275)(-3025 5225);
WIRE 16 -1 (-2825 5225)(-3025 5225);
WIRE 16 -1 (-3025 5225)(-3025 5175);
WIRE 16 -1 (-2825 5175)(-3025 5175);
WIRE 16 -1 (-3025 5175)(-3025 5125);
WIRE 16 -1 (-2825 5125)(-3025 5125);
WIRE 16 -1 (-3025 5125)(-3025 5075);
WIRE 16 -1 (-2825 5075)(-3025 5075);
WIRE 16 -1 (-3025 5075)(-3025 5025);
WIRE 16 -1 (-2825 5025)(-3025 5025);
WIRE 16 -1 (-3025 5025)(-3025 4975);
WIRE 16 -1 (-2825 4975)(-3025 4975);
WIRE 16 -1 (-3025 4975)(-3025 4925);
WIRE 16 -1 (-2825 4925)(-3025 4925);
WIRE 16 -1 (-3025 4925)(-3025 4875);
WIRE 16 -1 (-2825 4875)(-3025 4875);
WIRE 16 -1 (-3025 4875)(-3025 4825);
WIRE 16 -1 (-2825 4825)(-3025 4825);
WIRE 16 -1 (-3025 4825)(-3025 4775);
WIRE 16 -1 (-2825 4775)(-3025 4775);
WIRE 16 -1 (-3025 4775)(-3025 4725);
WIRE 16 -1 (-2825 4725)(-3025 4725);
WIRE 16 -1 (-3025 4725)(-3025 4675);
WIRE 16 -1 (-2825 4675)(-3025 4675);
WIRE 16 -1 (-3025 4675)(-3025 4625);
WIRE 16 -1 (-2825 4625)(-3025 4625);
WIRE 16 -1 (-3025 4625)(-3025 4575);
WIRE 16 -1 (-2825 4575)(-3025 4575);
WIRE 16 -1 (-3025 4575)(-3025 4525);
WIRE 16 -1 (-2825 4525)(-3025 4525);
WIRE 16 -1 (-3025 4525)(-3025 4475);
WIRE 16 -1 (-2825 4475)(-3025 4475);
WIRE 16 -1 (-3025 4475)(-3025 4425);
WIRE 16 -1 (-2825 4425)(-3025 4425);
WIRE 16 -1 (-3025 4425)(-3025 4375);
WIRE 16 -1 (-2825 4375)(-3025 4375);
WIRE 16 -1 (-3025 4375)(-3025 4325);
WIRE 16 -1 (-2825 4325)(-3025 4325);
WIRE 16 -1 (-3025 4325)(-3025 4275);
WIRE 16 -1 (-2825 4275)(-3025 4275);
WIRE 16 -1 (-3025 4275)(-3025 4225);
WIRE 16 -1 (-2825 4225)(-3025 4225);
WIRE 16 -1 (-3025 4225)(-3025 4175);
WIRE 16 -1 (-2825 4175)(-3025 4175);
WIRE 16 -1 (-3025 4175)(-3025 4125);
WIRE 16 -1 (-2825 4125)(-3025 4125);
WIRE 16 -1 (-3025 4125)(-3025 4075);
WIRE 16 -1 (-2825 4075)(-3025 4075);
WIRE 16 -1 (-3025 4075)(-3025 4025);
WIRE 16 -1 (-2825 4025)(-3025 4025);
WIRE 16 -1 (-3025 4025)(-3025 3975);
WIRE 16 -1 (-2825 3975)(-3025 3975);
WIRE 16 -1 (-3025 3975)(-3025 3925);
WIRE 16 -1 (-2825 3925)(-3025 3925);
WIRE 16 -1 (-3025 3925)(-3025 3875);
WIRE 16 -1 (-2825 3875)(-3025 3875);
WIRE 16 -1 (-3025 3875)(-3025 3825);
WIRE 16 -1 (-2825 3825)(-3025 3825);
WIRE 16 -1 (-3025 3825)(-3025 3775);
WIRE 16 -1 (-2825 3775)(-3025 3775);
WIRE 16 -1 (-3025 3775)(-3025 3725);
WIRE 16 -1 (-2825 3725)(-3025 3725);
WIRE 16 -1 (-3025 3725)(-3025 3675);
WIRE 16 -1 (-2825 3675)(-3025 3675);
WIRE 16 -1 (-3025 3675)(-3025 3625);
WIRE 16 -1 (-2825 3625)(-3025 3625);
WIRE 16 -1 (-3025 3625)(-3025 3575);
WIRE 16 -1 (-2825 3575)(-3025 3575);
WIRE 16 -1 (-3025 3575)(-3025 3525);
WIRE 16 -1 (-2825 3525)(-3025 3525);
WIRE 16 -1 (-3025 3525)(-3025 3475);
WIRE 16 -1 (-2825 3475)(-3025 3475);
WIRE 16 -1 (-3025 3475)(-3025 3425);
WIRE 16 -1 (-2825 3425)(-3025 3425);
WIRE 16 -1 (-3025 3425)(-3025 3375);
WIRE 16 -1 (-2825 3375)(-3025 3375);
WIRE 16 -1 (-3025 3375)(-3025 3325);
WIRE 16 -1 (-2825 3325)(-3025 3325);
WIRE 16 -1 (-3025 3325)(-3025 3275);
WIRE 16 -1 (-2825 3275)(-3025 3275);
WIRE 16 -1 (-3025 3275)(-3025 3225);
WIRE 16 -1 (-2825 3225)(-3025 3225);
WIRE 16 -1 (-3025 3225)(-3025 3175);
WIRE 16 -1 (-2825 3175)(-3025 3175);
WIRE 16 -1 (-3025 3175)(-3025 3125);
WIRE 16 -1 (-2825 3125)(-3025 3125);
WIRE 16 -1 (-3025 3125)(-3025 3075);
WIRE 16 -1 (-2825 3075)(-3025 3075);
WIRE 16 -1 (-3025 3075)(-3025 3025);
WIRE 16 -1 (-2825 3025)(-3025 3025);
WIRE 16 -1 (-3025 3025)(-3025 2975);
WIRE 16 -1 (-2825 2975)(-3025 2975);
WIRE 16 -1 (-3025 2975)(-3025 2925);
WIRE 16 -1 (-2825 2925)(-3025 2925);
WIRE 16 -1 (-3025 2925)(-3025 2875);
WIRE 16 -1 (-2825 2875)(-3025 2875);
WIRE 16 -1 (-3025 2875)(-3025 2825);
WIRE 16 -1 (-2825 2825)(-3025 2825);
WIRE 16 -1 (-3025 2825)(-3025 2775);
WIRE 16 -1 (-2825 2775)(-3025 2775);
WIRE 16 -1 (-3025 2775)(-3025 2725);
WIRE 16 -1 (-2825 2725)(-3025 2725);
WIRE 16 -1 (-3025 2725)(-3025 2675);
WIRE 16 -1 (-2825 2675)(-3025 2675);
WIRE 16 -1 (-3025 2675)(-3025 2625);
WIRE 16 -1 (-2825 2625)(-3025 2625);
WIRE 16 -1 (-3025 2625)(-3025 2575);
WIRE 16 -1 (-2825 2575)(-3025 2575);
WIRE 16 -1 (-3025 2575)(-3025 2525);
WIRE 16 -1 (-2825 2525)(-3025 2525);
WIRE 16 -1 (-3025 2525)(-3025 2475);
WIRE 16 -1 (-2825 2475)(-3025 2475);
WIRE 16 -1 (-3025 2475)(-3025 2425);
WIRE 16 -1 (-2825 2425)(-3025 2425);
WIRE 16 -1 (-3025 2425)(-3025 2375);
WIRE 16 -1 (-2825 2375)(-3025 2375);
WIRE 16 -1 (-3025 2375)(-3025 2325);
WIRE 16 -1 (-2825 2325)(-3025 2325);
WIRE 16 -1 (-3025 2325)(-3025 2275);
WIRE 16 -1 (-2825 2275)(-3025 2275);
WIRE 16 -1 (-3025 2275)(-3025 2225);
WIRE 16 -1 (-2825 2225)(-3025 2225);
WIRE 16 -1 (-3025 2225)(-3025 2175);
WIRE 16 -1 (-2825 2175)(-3025 2175);
WIRE 16 -1 (-3025 2175)(-3025 2125);
WIRE 16 -1 (-2825 2125)(-3025 2125);
WIRE 16 -1 (-3025 2125)(-3025 2075);
WIRE 16 -1 (-2825 2075)(-3025 2075);
WIRE 16 -1 (-3025 2075)(-3025 2025);
WIRE 16 -1 (-2825 2025)(-3025 2025);
WIRE 16 -1 (-3025 2025)(-3025 1975);
WIRE 16 -1 (-2825 1975)(-3025 1975);
WIRE 16 -1 (-3025 1975)(-3025 1925);
WIRE 16 -1 (-2825 1925)(-3025 1925);
WIRE 16 -1 (-3025 1925)(-3025 1875);
WIRE 16 -1 (-2825 1875)(-3025 1875);
WIRE 16 -1 (-3025 1875)(-3025 1825);
WIRE 16 -1 (-2825 1825)(-3025 1825);
WIRE 16 -1 (-3025 1825)(-3025 1775);
WIRE 16 -1 (-2825 1775)(-3025 1775);
WIRE 16 -1 (-3025 1775)(-3025 1725);
WIRE 16 -1 (-2825 1725)(-3025 1725);
WIRE 16 -1 (-3025 1725)(-3025 1675);
WIRE 16 -1 (-2825 1675)(-3025 1675);
WIRE 16 -1 (-3025 1675)(-3025 1625);
WIRE 16 -1 (-2825 1625)(-3025 1625);
WIRE 16 -1 (-3025 1625)(-3025 1575);
WIRE 16 -1 (-2825 1575)(-3025 1575);
WIRE 16 -1 (-3025 1575)(-3025 1525);
WIRE 16 -1 (-2825 1525)(-3025 1525);
WIRE 16 -1 (-3025 1525)(-3025 1475);
WIRE 16 -1 (-2825 1475)(-3025 1475);
WIRE 16 -1 (-3025 1475)(-3025 1325);
WIRE 16 -1 (-1875 2025)(-1200 2025);
FORCEPROP 2 LAST SIG_NAME NCF_A1_CPU0_P3_GND
J 0
(-1710 2035);
DISPLAY 0.553191 (-1710 2035);
PAINT SKYBLUE (-1710 2035);
FORCEPROP 2 LASTPROP $XRERR UNIQUE?
J 0
(-1950 2035);
DISPLAY 0.638298 (-1950 2035);
PAINT MONO (-1950 2035);
DISPLAY INVISIBLE (-1950 2035);
WIRE 16 -1 (-1200 2025)(-1200 1850);
WIRE 16 -1 (-1350 1975)(-1350 1925);
WIRE 16 -1 (-1350 1975)(-1875 1975);
FORCEPROP 2 LAST SIG_NAME NCF_CPU0_P3_GND
J 0
(-1760 1985);
DISPLAY 0.553191 (-1760 1985);
PAINT SKYBLUE (-1760 1985);
FORCEPROP 2 LASTPROP $XRERR UNIQUE?
J 0
(-2000 1985);
DISPLAY 0.638298 (-2000 1985);
PAINT MONO (-2000 1985);
DISPLAY INVISIBLE (-2000 1985);
WIRE 16 -1 (-1350 1925)(-1350 1875);
WIRE 16 -1 (-1350 1925)(-1875 1925);
WIRE 16 -1 (-1350 1875)(-1350 1825);
WIRE 16 -1 (-1350 1875)(-1875 1875);
WIRE 16 -1 (-1350 1825)(-1350 1775);
WIRE 16 -1 (-1350 1825)(-1875 1825);
WIRE 16 -1 (-1350 1775)(-1350 1725);
WIRE 16 -1 (-1350 1775)(-1875 1775);
WIRE 16 -1 (-1350 1725)(-1350 1675);
WIRE 16 -1 (-1350 1725)(-1875 1725);
WIRE 16 -1 (-1350 1675)(-1350 1625);
WIRE 16 -1 (-1350 1675)(-1875 1675);
WIRE 16 -1 (-1350 1625)(-1350 1575);
WIRE 16 -1 (-1350 1625)(-1875 1625);
WIRE 16 -1 (-1350 1575)(-1350 1525);
WIRE 16 -1 (-1350 1575)(-1875 1575);
WIRE 16 -1 (-1350 1525)(-1350 1475);
WIRE 16 -1 (-1350 1525)(-1875 1525);
WIRE 16 -1 (-1350 1475)(-1350 1300);
WIRE 16 -1 (-1350 1475)(-1875 1475);
WIRE 16 -1 (-1675 2125)(-1675 2100);
WIRE 16 -1 (-1675 2175)(-1675 2125);
WIRE 16 -1 (-1675 2125)(-1875 2125);
WIRE 16 -1 (-1675 2100)(-975 2100);
WIRE 16 -1 (-975 2100)(-975 2050);
WIRE 16 -1 (-1675 2225)(-1675 2175);
WIRE 16 -1 (-1675 2175)(-1875 2175);
WIRE 16 -1 (-1675 2275)(-1675 2225);
WIRE 16 -1 (-1675 2225)(-1875 2225);
WIRE 16 -1 (-1675 2325)(-1675 2275);
WIRE 16 -1 (-1675 2275)(-1875 2275);
WIRE 16 -1 (-1675 2375)(-1675 2325);
WIRE 16 -1 (-1675 2325)(-1875 2325);
WIRE 16 -1 (-1675 2425)(-1675 2375);
WIRE 16 -1 (-1675 2375)(-1875 2375);
WIRE 16 -1 (-1675 2475)(-1675 2425);
WIRE 16 -1 (-1675 2425)(-1875 2425);
WIRE 16 -1 (-1675 2525)(-1675 2475);
WIRE 16 -1 (-1675 2475)(-1875 2475);
WIRE 16 -1 (-1675 2575)(-1675 2525);
WIRE 16 -1 (-1675 2525)(-1875 2525);
WIRE 16 -1 (-1675 2625)(-1675 2575);
WIRE 16 -1 (-1675 2575)(-1875 2575);
WIRE 16 -1 (-1675 2675)(-1675 2625);
WIRE 16 -1 (-1675 2625)(-1875 2625);
WIRE 16 -1 (-1675 2725)(-1675 2675);
WIRE 16 -1 (-1675 2675)(-1875 2675);
WIRE 16 -1 (-1675 2775)(-1675 2725);
WIRE 16 -1 (-1675 2725)(-1875 2725);
WIRE 16 -1 (-1675 2825)(-1675 2775);
WIRE 16 -1 (-1675 2775)(-1875 2775);
WIRE 16 -1 (-1675 2875)(-1675 2825);
WIRE 16 -1 (-1675 2825)(-1875 2825);
WIRE 16 -1 (-1675 2925)(-1675 2875);
WIRE 16 -1 (-1675 2875)(-1875 2875);
WIRE 16 -1 (-1675 2975)(-1675 2925);
WIRE 16 -1 (-1675 2925)(-1875 2925);
WIRE 16 -1 (-1675 3025)(-1675 2975);
WIRE 16 -1 (-1675 2975)(-1875 2975);
WIRE 16 -1 (-1675 3075)(-1675 3025);
WIRE 16 -1 (-1675 3025)(-1875 3025);
WIRE 16 -1 (-1675 3125)(-1675 3075);
WIRE 16 -1 (-1675 3075)(-1875 3075);
WIRE 16 -1 (-1675 3175)(-1675 3125);
WIRE 16 -1 (-1675 3125)(-1875 3125);
WIRE 16 -1 (-1675 3225)(-1675 3175);
WIRE 16 -1 (-1675 3175)(-1875 3175);
WIRE 16 -1 (-1675 3275)(-1675 3225);
WIRE 16 -1 (-1675 3225)(-1875 3225);
WIRE 16 -1 (-1675 3325)(-1675 3275);
WIRE 16 -1 (-1675 3275)(-1875 3275);
WIRE 16 -1 (-1675 3375)(-1675 3325);
WIRE 16 -1 (-1675 3325)(-1875 3325);
WIRE 16 -1 (-1675 3425)(-1675 3375);
WIRE 16 -1 (-1675 3375)(-1875 3375);
WIRE 16 -1 (-1675 3475)(-1675 3425);
WIRE 16 -1 (-1675 3425)(-1875 3425);
WIRE 16 -1 (-1675 3525)(-1675 3475);
WIRE 16 -1 (-1675 3475)(-1875 3475);
WIRE 16 -1 (-1675 3575)(-1675 3525);
WIRE 16 -1 (-1675 3525)(-1875 3525);
WIRE 16 -1 (-1675 3625)(-1675 3575);
WIRE 16 -1 (-1675 3575)(-1875 3575);
WIRE 16 -1 (-1675 3675)(-1675 3625);
WIRE 16 -1 (-1675 3625)(-1875 3625);
WIRE 16 -1 (-1675 3725)(-1675 3675);
WIRE 16 -1 (-1675 3675)(-1875 3675);
WIRE 16 -1 (-1675 3775)(-1675 3725);
WIRE 16 -1 (-1675 3725)(-1875 3725);
WIRE 16 -1 (-1675 3825)(-1675 3775);
WIRE 16 -1 (-1675 3775)(-1875 3775);
WIRE 16 -1 (-1675 3875)(-1675 3825);
WIRE 16 -1 (-1675 3825)(-1875 3825);
WIRE 16 -1 (-1675 3925)(-1675 3875);
WIRE 16 -1 (-1675 3875)(-1875 3875);
WIRE 16 -1 (-1675 3975)(-1675 3925);
WIRE 16 -1 (-1675 3925)(-1875 3925);
WIRE 16 -1 (-1675 4025)(-1675 3975);
WIRE 16 -1 (-1675 3975)(-1875 3975);
WIRE 16 -1 (-1675 4075)(-1675 4025);
WIRE 16 -1 (-1675 4025)(-1875 4025);
WIRE 16 -1 (-1675 4125)(-1675 4075);
WIRE 16 -1 (-1675 4075)(-1875 4075);
WIRE 16 -1 (-1675 4175)(-1675 4125);
WIRE 16 -1 (-1675 4125)(-1875 4125);
WIRE 16 -1 (-1675 4225)(-1675 4175);
WIRE 16 -1 (-1675 4175)(-1875 4175);
WIRE 16 -1 (-1675 4275)(-1675 4225);
WIRE 16 -1 (-1675 4225)(-1875 4225);
WIRE 16 -1 (-1675 4325)(-1675 4275);
WIRE 16 -1 (-1675 4275)(-1875 4275);
WIRE 16 -1 (-1675 4375)(-1675 4325);
WIRE 16 -1 (-1675 4325)(-1875 4325);
WIRE 16 -1 (-1675 4425)(-1675 4375);
WIRE 16 -1 (-1675 4375)(-1875 4375);
WIRE 16 -1 (-1675 4475)(-1675 4425);
WIRE 16 -1 (-1675 4425)(-1875 4425);
WIRE 16 -1 (-1675 4525)(-1675 4475);
WIRE 16 -1 (-1675 4475)(-1875 4475);
WIRE 16 -1 (-1675 4575)(-1675 4525);
WIRE 16 -1 (-1675 4525)(-1875 4525);
WIRE 16 -1 (-1675 4625)(-1675 4575);
WIRE 16 -1 (-1675 4575)(-1875 4575);
WIRE 16 -1 (-1675 4675)(-1675 4625);
WIRE 16 -1 (-1675 4625)(-1875 4625);
WIRE 16 -1 (-1675 4725)(-1675 4675);
WIRE 16 -1 (-1675 4675)(-1875 4675);
WIRE 16 -1 (-1675 4775)(-1675 4725);
WIRE 16 -1 (-1675 4725)(-1875 4725);
WIRE 16 -1 (-1675 4825)(-1675 4775);
WIRE 16 -1 (-1675 4775)(-1875 4775);
WIRE 16 -1 (-1675 4875)(-1675 4825);
WIRE 16 -1 (-1675 4825)(-1875 4825);
WIRE 16 -1 (-1675 4925)(-1675 4875);
WIRE 16 -1 (-1675 4875)(-1875 4875);
WIRE 16 -1 (-1675 4975)(-1675 4925);
WIRE 16 -1 (-1675 4925)(-1875 4925);
WIRE 16 -1 (-1675 5025)(-1675 4975);
WIRE 16 -1 (-1675 4975)(-1875 4975);
WIRE 16 -1 (-1675 5075)(-1675 5025);
WIRE 16 -1 (-1675 5025)(-1875 5025);
WIRE 16 -1 (-1675 5125)(-1675 5075);
WIRE 16 -1 (-1675 5075)(-1875 5075);
WIRE 16 -1 (-1675 5175)(-1675 5125);
WIRE 16 -1 (-1675 5125)(-1875 5125);
WIRE 16 -1 (-1675 5225)(-1675 5175);
WIRE 16 -1 (-1675 5175)(-1875 5175);
WIRE 16 -1 (-1675 5275)(-1675 5225);
WIRE 16 -1 (-1675 5225)(-1875 5225);
WIRE 16 -1 (-1675 5325)(-1675 5275);
WIRE 16 -1 (-1675 5275)(-1875 5275);
WIRE 16 -1 (-1675 5375)(-1675 5325);
WIRE 16 -1 (-1675 5325)(-1875 5325);
WIRE 16 -1 (-1675 5425)(-1675 5375);
WIRE 16 -1 (-1675 5375)(-1875 5375);
WIRE 16 -1 (-1675 5475)(-1675 5425);
WIRE 16 -1 (-1675 5425)(-1875 5425);
WIRE 16 -1 (-1675 5525)(-1675 5475);
WIRE 16 -1 (-1675 5475)(-1875 5475);
WIRE 16 -1 (-1675 5525)(-1875 5525);
WIRE 16 -1 (-5525 3500)(-5525 3450);
WIRE 16 -1 (-5525 3550)(-5525 3500);
WIRE 16 -1 (-5850 3500)(-5525 3500);
WIRE 16 -1 (-5525 3450)(-5850 3450);
WIRE 16 -1 (-5525 3600)(-5525 3550);
WIRE 16 -1 (-5850 3550)(-5525 3550);
WIRE 16 -1 (-5525 3600)(-4550 3600);
WIRE 16 -1 (-5850 3600)(-5525 3600);
WIRE 16 -1 (-4550 3700)(-4550 3600);
WIRE 16 -1 (-7000 4050)(-8250 4050);
WIRE 16 -1 (-8250 4300)(-8250 4050);
WIRE 16 -1 (-8575 3750)(-8575 3600);
WIRE 16 -1 (-7550 3600)(-8575 3600);
FORCEPROP 2 LAST SIG_NAME RT_CPU0_P3_VQPS
J 0
(-7760 3610);
DISPLAY 0.680851 (-7760 3610);
PAINT SKYBLUE (-7760 3610);
FORCEPROP 2 LASTPROP $XRERR UNIQUE?
J 0
(-8000 3610);
DISPLAY 0.638298 (-8000 3610);
PAINT MONO (-8000 3610);
DISPLAY INVISIBLE (-8000 3610);
WIRE 16 -1 (-7000 3600)(-7550 3600);
WIRE 16 -1 (-7550 3600)(-7550 3400);
DOT 1 (-1675 2175);
DOT 1 (-1350 1925);
DOT 1 (-5600 3850);
DOT 1 (-5625 4700);
DOT 1 (-7425 4700);
DOT 1 (-5600 3950);
DOT 1 (-1350 1725);
DOT 1 (-5600 4200);
DOT 1 (-5525 3500);
DOT 1 (-5525 3550);
DOT 1 (-5600 3800);
DOT 1 (-5600 3900);
DOT 1 (-5600 4050);
DOT 1 (-5600 4000);
DOT 1 (-5600 4100);
DOT 1 (-5600 4150);
DOT 1 (-7425 4650);
DOT 1 (-7425 4600);
DOT 1 (-7425 4550);
DOT 1 (-5600 4300);
DOT 1 (-5600 4350);
DOT 1 (-5600 4400);
DOT 1 (-5625 4600);
DOT 1 (-5625 4650);
DOT 1 (-5625 4500);
DOT 1 (-4575 4700);
DOT 1 (-3025 1525);
DOT 1 (-3025 1475);
DOT 1 (-3025 1625);
DOT 1 (-3025 1575);
DOT 1 (-3025 1725);
DOT 1 (-3025 1675);
DOT 1 (-3025 1775);
DOT 1 (-3025 1875);
DOT 1 (-3025 1825);
DOT 1 (-3025 1925);
DOT 1 (-3025 1975);
DOT 1 (-3025 2025);
DOT 1 (-3025 2125);
DOT 1 (-3025 2075);
DOT 1 (-3025 2175);
DOT 1 (-3025 2225);
DOT 1 (-3025 2275);
DOT 1 (-3025 2325);
DOT 1 (-3025 2375);
DOT 1 (-3025 2425);
DOT 1 (-3025 2525);
DOT 1 (-3025 2475);
DOT 1 (-3025 2575);
DOT 1 (-3025 2625);
DOT 1 (-3025 2675);
DOT 1 (-3025 2775);
DOT 1 (-3025 2725);
DOT 1 (-3025 2825);
DOT 1 (-3025 2875);
DOT 1 (-3025 2925);
DOT 1 (-3025 3025);
DOT 1 (-3025 2975);
DOT 1 (-3025 3075);
DOT 1 (-3025 3125);
DOT 1 (-3025 3175);
DOT 1 (-3025 3325);
DOT 1 (-3025 3275);
DOT 1 (-3025 3225);
DOT 1 (-3025 3425);
DOT 1 (-3025 3375);
DOT 1 (-3025 3475);
DOT 1 (-3025 3525);
DOT 1 (-3025 3575);
DOT 1 (-3025 3675);
DOT 1 (-3025 3625);
DOT 1 (-3025 3725);
DOT 1 (-3025 3775);
DOT 1 (-3025 3825);
DOT 1 (-3025 3925);
DOT 1 (-3025 3875);
DOT 1 (-3025 3975);
DOT 1 (-3025 4025);
DOT 1 (-3025 4175);
DOT 1 (-3025 4125);
DOT 1 (-1350 1475);
DOT 1 (-1350 1525);
DOT 1 (-1350 1625);
DOT 1 (-1350 1575);
DOT 1 (-1350 1675);
DOT 1 (-1350 1775);
DOT 1 (-1350 1825);
DOT 1 (-1350 1875);
DOT 1 (-1675 2275);
DOT 1 (-1675 2225);
DOT 1 (-1675 2325);
DOT 1 (-1675 2375);
DOT 1 (-1675 2425);
DOT 1 (-1675 2525);
DOT 1 (-1675 2475);
DOT 1 (-1675 2675);
DOT 1 (-1675 2575);
DOT 1 (-1675 2625);
DOT 1 (-1675 2725);
DOT 1 (-1675 2775);
DOT 1 (-1675 2825);
DOT 1 (-1675 2875);
DOT 1 (-1675 2925);
DOT 1 (-1675 2975);
DOT 1 (-1675 3025);
DOT 1 (-1675 3075);
DOT 1 (-1675 3125);
DOT 1 (-1675 3175);
DOT 1 (-1675 3225);
DOT 1 (-1675 3275);
DOT 1 (-1675 3325);
DOT 1 (-1675 3375);
DOT 1 (-1675 3425);
DOT 1 (-1675 3475);
DOT 1 (-1675 3525);
DOT 1 (-1675 3575);
DOT 1 (-1675 3625);
DOT 1 (-1675 3675);
DOT 1 (-1675 3725);
DOT 1 (-1675 3775);
DOT 1 (-1675 3825);
DOT 1 (-1675 3875);
DOT 1 (-1675 3925);
DOT 1 (-1675 3975);
DOT 1 (-1675 4025);
DOT 1 (-1675 4075);
DOT 1 (-1675 4125);
DOT 1 (-1675 4175);
DOT 1 (-1675 4225);
DOT 1 (-3025 4225);
DOT 1 (-3025 4275);
DOT 1 (-3025 4325);
DOT 1 (-3025 4375);
DOT 1 (-3025 4425);
DOT 1 (-3025 4475);
DOT 1 (-3025 4575);
DOT 1 (-3025 4525);
DOT 1 (-3025 4625);
DOT 1 (-3025 4675);
DOT 1 (-3025 4725);
DOT 1 (-3025 4825);
DOT 1 (-3025 4775);
DOT 1 (-3025 4925);
DOT 1 (-3025 4875);
DOT 1 (-3025 4975);
DOT 1 (-3025 5075);
DOT 1 (-3025 5025);
DOT 1 (-3025 5125);
DOT 1 (-3025 5175);
DOT 1 (-3025 5225);
DOT 1 (-3025 5325);
DOT 1 (-3025 5275);
DOT 1 (-3025 5375);
DOT 1 (-3025 5475);
DOT 1 (-1675 4275);
DOT 1 (-1675 4325);
DOT 1 (-1675 4375);
DOT 1 (-1675 4425);
DOT 1 (-1675 4475);
DOT 1 (-1675 4525);
DOT 1 (-1675 4575);
DOT 1 (-1675 4625);
DOT 1 (-1675 4675);
DOT 1 (-1675 4725);
DOT 1 (-1675 4775);
DOT 1 (-1675 4825);
DOT 1 (-1675 4875);
DOT 1 (-1675 4925);
DOT 1 (-1675 4975);
DOT 1 (-1675 5025);
DOT 1 (-1675 5075);
DOT 1 (-1675 5125);
DOT 1 (-1675 5175);
DOT 1 (-1675 5225);
DOT 1 (-1675 5275);
DOT 1 (-1675 5325);
DOT 1 (-1675 5375);
DOT 1 (-1675 5425);
DOT 1 (-1675 5475);
DOT 1 (-1675 2125);
DOT 1 (-5625 4550);
DOT 1 (-3025 4075);
DOT 1 (-3025 5425);
DOT 1 (-5525 3600);
DOT 1 (-7550 3600);
QUIT
